# S9S_MB_2U (Grand Teton) — schematic netlist excerpt (pin names and nets, part order shuffled) for the footprints in the layout excerpt that follows; sources: Cadence DE-HDL packaged netlist, KiCad conversion of 03242023_DA0F0TMBIJ0_F0T_Motherboard_J_brd_V01_OCP.brd

R3101  Q_RES  470 1% CHIP  pkg 0402LF  page 252 : A = LED_P5V_AUX ; B = P5V_AUX
C1010  Q_CAP  22UF 4V 20% X6S  pkg C0402  page 74 : A = PVCCIN_CPU0 ; B = GND

(kicad_pcb
	(version 20260206)
	(generator "pcbnew")
	(generator_version "10.0")
	(general
		(thickness 1.6)
		(legacy_teardrops no)
	)
	(paper "A4")
	(title_block
		(title "03242023_DA0F0TMBIJ0_F0T_Motherboard_J_brd_V01_OCP.brd")
		(comment 1 "Grand Teton / footprints 4056-4057 of 6105")
	)
	(layers
		(0 "F.Cu" signal "TOP")
		(4 "In1.Cu" signal "GND")
		(6 "In2.Cu" signal "IN1")
		(8 "In3.Cu" signal "GND1")
		(10 "In4.Cu" signal "IN2")
		(12 "In5.Cu" signal "GND2")
		(14 "In6.Cu" signal "IN3")
		(16 "In7.Cu" signal "GND3")
		(18 "In8.Cu" signal "VCC")
		(20 "In9.Cu" signal "VCC1")
		(22 "In10.Cu" signal "GND4")
		(24 "In11.Cu" signal "IN4")
		(26 "In12.Cu" signal "GND5")
		(28 "In13.Cu" signal "IN5")
		(30 "In14.Cu" signal "GND6")
		(32 "In15.Cu" signal "IN6")
		(34 "In16.Cu" signal "GND7")
		(2 "B.Cu" signal "BOTTOM")
		(9 "F.Adhes" user "F.Adhesive")
		(11 "B.Adhes" user "B.Adhesive")
		(13 "F.Paste" user "Package Geometry/Pastemask Top")
		(15 "B.Paste" user "Package Geometry/Pastemask Bottom")
		(5 "F.SilkS" user "Ref Des/Silkscreen Top")
		(7 "B.SilkS" user "Ref Des/Silkscreen Bottom")
		(1 "F.Mask" user "Board Geometry/Soldermask Top")
		(3 "B.Mask" user "Board Geometry/Soldermask Bottom")
		(17 "Dwgs.User" user "User.Drawings")
		(19 "Cmts.User" user "User.Comments")
		(21 "Eco1.User" user "User.Eco1")
		(23 "Eco2.User" user "User.Eco2")
		(25 "Edge.Cuts" user "Board Geometry/Outline")
		(27 "Margin" user)
		(31 "F.CrtYd" user "Package Geometry/Place Bound Top")
		(29 "B.CrtYd" user "Package Geometry/Place Bound Bottom")
		(35 "F.Fab" user "Ref Des/Assembly Top")
		(33 "B.Fab" user "Ref Des/Assembly Bottom")
	)
	(footprint ""
		(layer "F.Cu")
		(at 355.229414 -252.956314 -90)
		(property "Reference" "C1010"
			(at 0 0 270)
			(layer "F.SilkS")
			(hide yes)
			(effects
				(font
					(size 1.27 1.27)
				)
			)
		)
		(property "Value" ""
			(at 0 0 270)
			(layer "F.Fab")
			(effects
				(font
					(size 1.27 1.27)
				)
			)
		)
		(duplicate_pad_numbers_are_jumpers no)
		(fp_line
			(start -0.7874 0.4064)
			(end -0.7874 -0.4064)
			(stroke
				(width 0.1524)
				(type default)
			)
			(layer "F.SilkS")
		)
		(fp_line
			(start 0.7874 0.4064)
			(end -0.7874 0.4064)
			(stroke
				(width 0.1524)
				(type default)
			)
			(layer "F.SilkS")
		)
		(fp_line
			(start -0.7874 -0.4064)
			(end 0.7874 -0.4064)
			(stroke
				(width 0.1524)
				(type default)
			)
			(layer "F.SilkS")
		)
		(fp_line
			(start 0.7874 -0.4064)
			(end 0.7874 0.4064)
			(stroke
				(width 0.1524)
				(type default)
			)
			(layer "F.SilkS")
		)
		(fp_line
			(start -0.67945 0.3048)
			(end -0.67945 -0.305054)
			(stroke
				(width 0.1)
				(type default)
			)
			(layer "F.Fab")
		)
		(fp_line
			(start -0.12065 0.3048)
			(end -0.67945 0.3048)
			(stroke
				(width 0.1)
				(type default)
			)
			(layer "F.Fab")
		)
		(fp_line
			(start 0.120396 0.3048)
			(end 0.120396 0.2794)
			(stroke
				(width 0.1)
				(type default)
			)
			(layer "F.Fab")
		)
		(fp_line
			(start 0.67945 0.3048)
			(end 0.120396 0.3048)
			(stroke
				(width 0.1)
				(type default)
			)
			(layer "F.Fab")
		)
		(fp_line
			(start -0.12065 0.2794)
			(end -0.12065 0.3048)
			(stroke
				(width 0.1)
				(type default)
			)
			(layer "F.Fab")
		)
		(fp_line
			(start 0.120396 0.2794)
			(end -0.12065 0.2794)
			(stroke
				(width 0.1)
				(type default)
			)
			(layer "F.Fab")
		)
		(fp_line
			(start -0.12065 -0.2794)
			(end 0.12065 -0.2794)
			(stroke
				(width 0.1)
				(type default)
			)
			(layer "F.Fab")
		)
		(fp_line
			(start 0.12065 -0.2794)
			(end 0.12065 -0.3048)
			(stroke
				(width 0.1)
				(type default)
			)
			(layer "F.Fab")
		)
		(fp_line
			(start 0.12065 -0.3048)
			(end 0.67945 -0.3048)
			(stroke
				(width 0.1)
				(type default)
			)
			(layer "F.Fab")
		)
		(fp_line
			(start 0.67945 -0.3048)
			(end 0.67945 0.3048)
			(stroke
				(width 0.1)
				(type default)
			)
			(layer "F.Fab")
		)
		(fp_line
			(start -0.67945 -0.305054)
			(end -0.12065 -0.305054)
			(stroke
				(width 0.1)
				(type default)
			)
			(layer "F.Fab")
		)
		(fp_line
			(start -0.12065 -0.305054)
			(end -0.12065 -0.2794)
			(stroke
				(width 0.1)
				(type default)
			)
			(layer "F.Fab")
		)
		(pad "1" smd circle
			(at -0.40005 0 270)
			(size 0 0)
			(layers "F.Cu" "F.Mask" "F.Paste")
			(net "PVCCIN_CPU0")
		)
		(pad "2" smd circle
			(at 0.40005 0 270)
			(size 0 0)
			(layers "F.Cu" "F.Mask" "F.Paste")
			(net "GND")
		)
	)
	(footprint ""
		(layer "F.Cu")
		(at 112.33531 -74.908156 -90)
		(property "Reference" "R3101"
			(at 0 0 270)
			(layer "F.SilkS")
			(hide yes)
			(effects
				(font
					(size 1.27 1.27)
				)
			)
		)
		(property "Value" ""
			(at 0 0 270)
			(layer "F.Fab")
			(effects
				(font
					(size 1.27 1.27)
				)
			)
		)
		(duplicate_pad_numbers_are_jumpers no)
		(fp_line
			(start -0.7874 0.4064)
			(end -0.7874 -0.4064)
			(stroke
				(width 0.1524)
				(type default)
			)
			(layer "F.SilkS")
		)
		(fp_line
			(start 0.7874 0.4064)
			(end -0.7874 0.4064)
			(stroke
				(width 0.1524)
				(type default)
			)
			(layer "F.SilkS")
		)
		(fp_line
			(start -0.7874 -0.4064)
			(end 0.7874 -0.4064)
			(stroke
				(width 0.1524)
				(type default)
			)
			(layer "F.SilkS")
		)
		(fp_line
			(start 0.7874 -0.4064)
			(end 0.7874 0.4064)
			(stroke
				(width 0.1524)
				(type default)
			)
			(layer "F.SilkS")
		)
		(fp_line
			(start -0.67945 0.3048)
			(end -0.67945 -0.305054)
			(stroke
				(width 0.1)
				(type default)
			)
			(layer "F.Fab")
		)
		(fp_line
			(start -0.12065 0.3048)
			(end -0.67945 0.3048)
			(stroke
				(width 0.1)
				(type default)
			)
			(layer "F.Fab")
		)
		(fp_line
			(start 0.120396 0.3048)
			(end 0.120396 0.2794)
			(stroke
				(width 0.1)
				(type default)
			)
			(layer "F.Fab")
		)
		(fp_line
			(start 0.67945 0.3048)
			(end 0.120396 0.3048)
			(stroke
				(width 0.1)
				(type default)
			)
			(layer "F.Fab")
		)
		(fp_line
			(start -0.12065 0.2794)
			(end -0.12065 0.3048)
			(stroke
				(width 0.1)
				(type default)
			)
			(layer "F.Fab")
		)
		(fp_line
			(start 0.120396 0.2794)
			(end -0.12065 0.2794)
			(stroke
				(width 0.1)
				(type default)
			)
			(layer "F.Fab")
		)
		(fp_line
			(start -0.12065 -0.2794)
			(end 0.12065 -0.2794)
			(stroke
				(width 0.1)
				(type default)
			)
			(layer "F.Fab")
		)
		(fp_line
			(start 0.12065 -0.2794)
			(end 0.12065 -0.3048)
			(stroke
				(width 0.1)
				(type default)
			)
			(layer "F.Fab")
		)
		(fp_line
			(start 0.12065 -0.3048)
			(end 0.67945 -0.3048)
			(stroke
				(width 0.1)
				(type default)
			)
			(layer "F.Fab")
		)
		(fp_line
			(start 0.67945 -0.3048)
			(end 0.67945 0.3048)
			(stroke
				(width 0.1)
				(type default)
			)
			(layer "F.Fab")
		)
		(fp_line
			(start -0.67945 -0.305054)
			(end -0.12065 -0.305054)
			(stroke
				(width 0.1)
				(type default)
			)
			(layer "F.Fab")
		)
		(fp_line
			(start -0.12065 -0.305054)
			(end -0.12065 -0.2794)
			(stroke
				(width 0.1)
				(type default)
			)
			(layer "F.Fab")
		)
		(pad "1" smd circle
			(at -0.40005 0 270)
			(size 0 0)
			(layers "F.Cu" "F.Mask" "F.Paste")
			(net "LED_P5V_AUX")
		)
		(pad "2" smd circle
			(at 0.40005 0 270)
			(size 0 0)
			(layers "F.Cu" "F.Mask" "F.Paste")
			(net "P5V_AUX")
		)
	)
)
